(kicad_pcb
	(version 20260206)
	(generator "pcbnew")
	(generator_version "10.0")
	(general
		(thickness 1.6)
		(legacy_teardrops no)
	)
	(paper "A4")
	(title_block
		(title "01162023_DA0F0TEBIF0_F0T_Expander_BD_F_brd_V02_OCP.brd")
		(comment 1 "Grand Teton / footprints 205-210 of 9728")
	)
	(layers
		(0 "F.Cu" signal "TOP")
		(4 "In1.Cu" signal "GND")
		(6 "In2.Cu" signal "VCC")
		(8 "In3.Cu" signal "VCC1")
		(10 "In4.Cu" signal "GND1")
		(12 "In5.Cu" signal "IN1")
		(14 "In6.Cu" signal "GND2")
		(16 "In7.Cu" signal "IN2")
		(18 "In8.Cu" signal "GND3")
		(20 "In9.Cu" signal "IN3")
		(22 "In10.Cu" signal "GND4")
		(24 "In11.Cu" signal "IN4")
		(26 "In12.Cu" signal "GND5")
		(28 "In13.Cu" signal "IN5")
		(30 "In14.Cu" signal "GND6")
		(32 "In15.Cu" signal "IN6")
		(34 "In16.Cu" signal "GND7")
		(2 "B.Cu" signal "BOTTOM")
		(9 "F.Adhes" user "F.Adhesive")
		(11 "B.Adhes" user "B.Adhesive")
		(13 "F.Paste" user "Package Geometry/Pastemask Top")
		(15 "B.Paste" user "Package Geometry/Pastemask Bottom")
		(5 "F.SilkS" user "Ref Des/Silkscreen Top")
		(7 "B.SilkS" user "Ref Des/Silkscreen Bottom")
		(1 "F.Mask" user "Board Geometry/Soldermask Top")
		(3 "B.Mask" user "Board Geometry/Soldermask Bottom")
		(17 "Dwgs.User" user "User.Drawings")
		(19 "Cmts.User" user "User.Comments")
		(21 "Eco1.User" user "User.Eco1")
		(23 "Eco2.User" user "User.Eco2")
		(25 "Edge.Cuts" user "Board Geometry/Outline")
		(27 "Margin" user)
		(31 "F.CrtYd" user "Package Geometry/Place Bound Top")
		(29 "B.CrtYd" user "Package Geometry/Place Bound Bottom")
		(35 "F.Fab" user "Ref Des/Assembly Top")
		(33 "B.Fab" user "Ref Des/Assembly Bottom")
	)
	(footprint ""
		(layer "F.Cu")
		(at 256.542286 -250.070874 -90)
		(property "Reference" "R1345"
			(at 0 0 270)
			(layer "F.SilkS")
			(hide yes)
			(effects
				(font
					(size 1.27 1.27)
				)
			)
		)
		(property "Value" ""
			(at 0 0 270)
			(layer "F.Fab")
			(effects
				(font
					(size 1.27 1.27)
				)
			)
		)
		(duplicate_pad_numbers_are_jumpers no)
		(fp_line
			(start -0.7874 0.4064)
			(end -0.7874 -0.4064)
			(stroke
				(width 0.1524)
				(type default)
			)
			(layer "F.SilkS")
		)
		(fp_line
			(start 0.7874 0.4064)
			(end -0.7874 0.4064)
			(stroke
				(width 0.1524)
				(type default)
			)
			(layer "F.SilkS")
		)
		(fp_line
			(start -0.7874 -0.4064)
			(end 0.7874 -0.4064)
			(stroke
				(width 0.1524)
				(type default)
			)
			(layer "F.SilkS")
		)
		(fp_line
			(start 0.7874 -0.4064)
			(end 0.7874 0.4064)
			(stroke
				(width 0.1524)
				(type default)
			)
			(layer "F.SilkS")
		)
		(fp_line
			(start -0.67945 0.3048)
			(end -0.67945 -0.305054)
			(stroke
				(width 0.1)
				(type default)
			)
			(layer "F.Fab")
		)
		(fp_line
			(start -0.12065 0.3048)
			(end -0.67945 0.3048)
			(stroke
				(width 0.1)
				(type default)
			)
			(layer "F.Fab")
		)
		(fp_line
			(start 0.120396 0.3048)
			(end 0.120396 0.2794)
			(stroke
				(width 0.1)
				(type default)
			)
			(layer "F.Fab")
		)
		(fp_line
			(start 0.67945 0.3048)
			(end 0.120396 0.3048)
			(stroke
				(width 0.1)
				(type default)
			)
			(layer "F.Fab")
		)
		(fp_line
			(start -0.12065 0.2794)
			(end -0.12065 0.3048)
			(stroke
				(width 0.1)
				(type default)
			)
			(layer "F.Fab")
		)
		(fp_line
			(start 0.120396 0.2794)
			(end -0.12065 0.2794)
			(stroke
				(width 0.1)
				(type default)
			)
			(layer "F.Fab")
		)
		(fp_line
			(start -0.12065 -0.2794)
			(end 0.12065 -0.2794)
			(stroke
				(width 0.1)
				(type default)
			)
			(layer "F.Fab")
		)
		(fp_line
			(start 0.12065 -0.2794)
			(end 0.12065 -0.3048)
			(stroke
				(width 0.1)
				(type default)
			)
			(layer "F.Fab")
		)
		(fp_line
			(start 0.12065 -0.3048)
			(end 0.67945 -0.3048)
			(stroke
				(width 0.1)
				(type default)
			)
			(layer "F.Fab")
		)
		(fp_line
			(start 0.67945 -0.3048)
			(end 0.67945 0.3048)
			(stroke
				(width 0.1)
				(type default)
			)
			(layer "F.Fab")
		)
		(fp_line
			(start -0.67945 -0.305054)
			(end -0.12065 -0.305054)
			(stroke
				(width 0.1)
				(type default)
			)
			(layer "F.Fab")
		)
		(fp_line
			(start -0.12065 -0.305054)
			(end -0.12065 -0.2794)
			(stroke
				(width 0.1)
				(type default)
			)
			(layer "F.Fab")
		)
		(pad "1" smd circle
			(at -0.40005 0 270)
			(size 0 0)
			(layers "F.Cu" "F.Mask" "F.Paste")
			(net "PEX2_MODE_SEL9")
		)
		(pad "2" smd circle
			(at 0.40005 0 270)
			(size 0 0)
			(layers "F.Cu" "F.Mask" "F.Paste")
			(net "P1V8_PEX")
		)
	)
	(footprint ""
		(layer "F.Cu")
		(at 101.703886 -219.559886)
		(property "Reference" "R849"
			(at 0 0 0)
			(layer "F.SilkS")
			(hide yes)
			(effects
				(font
					(size 1.27 1.27)
				)
			)
		)
		(property "Value" ""
			(at 0 0 0)
			(layer "F.Fab")
			(effects
				(font
					(size 1.27 1.27)
				)
			)
		)
		(duplicate_pad_numbers_are_jumpers no)
		(fp_line
			(start -0.7874 -0.4064)
			(end 0.7874 -0.4064)
			(stroke
				(width 0.1524)
				(type default)
			)
			(layer "F.SilkS")
		)
		(fp_line
			(start -0.7874 0.4064)
			(end -0.7874 -0.4064)
			(stroke
				(width 0.1524)
				(type default)
			)
			(layer "F.SilkS")
		)
		(fp_line
			(start 0.7874 -0.4064)
			(end 0.7874 0.4064)
			(stroke
				(width 0.1524)
				(type default)
			)
			(layer "F.SilkS")
		)
		(fp_line
			(start 0.7874 0.4064)
			(end -0.7874 0.4064)
			(stroke
				(width 0.1524)
				(type default)
			)
			(layer "F.SilkS")
		)
		(fp_line
			(start -0.67945 -0.305054)
			(end -0.12065 -0.305054)
			(stroke
				(width 0.1)
				(type default)
			)
			(layer "F.Fab")
		)
		(fp_line
			(start -0.67945 0.3048)
			(end -0.67945 -0.305054)
			(stroke
				(width 0.1)
				(type default)
			)
			(layer "F.Fab")
		)
		(fp_line
			(start -0.12065 -0.305054)
			(end -0.12065 -0.2794)
			(stroke
				(width 0.1)
				(type default)
			)
			(layer "F.Fab")
		)
		(fp_line
			(start -0.12065 -0.2794)
			(end 0.12065 -0.2794)
			(stroke
				(width 0.1)
				(type default)
			)
			(layer "F.Fab")
		)
		(fp_line
			(start -0.12065 0.2794)
			(end -0.12065 0.3048)
			(stroke
				(width 0.1)
				(type default)
			)
			(layer "F.Fab")
		)
		(fp_line
			(start -0.12065 0.3048)
			(end -0.67945 0.3048)
			(stroke
				(width 0.1)
				(type default)
			)
			(layer "F.Fab")
		)
		(fp_line
			(start 0.120396 0.2794)
			(end -0.12065 0.2794)
			(stroke
				(width 0.1)
				(type default)
			)
			(layer "F.Fab")
		)
		(fp_line
			(start 0.120396 0.3048)
			(end 0.120396 0.2794)
			(stroke
				(width 0.1)
				(type default)
			)
			(layer "F.Fab")
		)
		(fp_line
			(start 0.12065 -0.3048)
			(end 0.67945 -0.3048)
			(stroke
				(width 0.1)
				(type default)
			)
			(layer "F.Fab")
		)
		(fp_line
			(start 0.12065 -0.2794)
			(end 0.12065 -0.3048)
			(stroke
				(width 0.1)
				(type default)
			)
			(layer "F.Fab")
		)
		(fp_line
			(start 0.67945 -0.3048)
			(end 0.67945 0.3048)
			(stroke
				(width 0.1)
				(type default)
			)
			(layer "F.Fab")
		)
		(fp_line
			(start 0.67945 0.3048)
			(end 0.120396 0.3048)
			(stroke
				(width 0.1)
				(type default)
			)
			(layer "F.Fab")
		)
		(pad "1" smd circle
			(at -0.40005 0)
			(size 0 0)
			(layers "F.Cu" "F.Mask" "F.Paste")
			(net "P1V8_PEX_VCC")
		)
		(pad "2" smd circle
			(at 0.40005 0)
			(size 0 0)
			(layers "F.Cu" "F.Mask" "F.Paste")
			(net "PWRGD_P1V8_PEX")
		)
	)
	(footprint ""
		(layer "F.Cu")
		(at 381.340106 -259.834634 180)
		(property "Reference" "C3570"
			(at 0 0 180)
			(layer "F.SilkS")
			(hide yes)
			(effects
				(font
					(size 1.27 1.27)
				)
			)
		)
		(property "Value" ""
			(at 0 0 180)
			(layer "F.Fab")
			(effects
				(font
					(size 1.27 1.27)
				)
			)
		)
		(duplicate_pad_numbers_are_jumpers no)
		(fp_line
			(start 1.2954 0.5842)
			(end -1.2954 0.5842)
			(stroke
				(width 0.1524)
				(type default)
			)
			(layer "F.SilkS")
		)
		(fp_line
			(start 1.2954 -0.5842)
			(end 1.2954 0.5842)
			(stroke
				(width 0.1524)
				(type default)
			)
			(layer "F.SilkS")
		)
		(fp_line
			(start -1.2954 0.5842)
			(end -1.2954 -0.5842)
			(stroke
				(width 0.1524)
				(type default)
			)
			(layer "F.SilkS")
		)
		(fp_line
			(start -1.2954 -0.5842)
			(end 1.2954 -0.5842)
			(stroke
				(width 0.1524)
				(type default)
			)
			(layer "F.SilkS")
		)
		(fp_line
			(start 1.1938 0.4064)
			(end 0.8636 0.4064)
			(stroke
				(width 0.1)
				(type default)
			)
			(layer "F.Fab")
		)
		(fp_line
			(start 1.1938 -0.4064)
			(end 1.1938 0.4064)
			(stroke
				(width 0.1)
				(type default)
			)
			(layer "F.Fab")
		)
		(fp_line
			(start 0.8636 0.4572)
			(end -0.8636 0.4572)
			(stroke
				(width 0.1)
				(type default)
			)
			(layer "F.Fab")
		)
		(fp_line
			(start 0.8636 0.4064)
			(end 0.8636 0.4572)
			(stroke
				(width 0.1)
				(type default)
			)
			(layer "F.Fab")
		)
		(fp_line
			(start 0.8636 -0.4064)
			(end 1.1938 -0.4064)
			(stroke
				(width 0.1)
				(type default)
			)
			(layer "F.Fab")
		)
		(fp_line
			(start 0.8636 -0.4572)
			(end 0.8636 -0.4064)
			(stroke
				(width 0.1)
				(type default)
			)
			(layer "F.Fab")
		)
		(fp_line
			(start -0.8636 0.4572)
			(end -0.8636 0.4064)
			(stroke
				(width 0.1)
				(type default)
			)
			(layer "F.Fab")
		)
		(fp_line
			(start -0.8636 0.4064)
			(end -1.1938 0.4064)
			(stroke
				(width 0.1)
				(type default)
			)
			(layer "F.Fab")
		)
		(fp_line
			(start -0.8636 -0.4064)
			(end -0.8636 -0.4572)
			(stroke
				(width 0.1)
				(type default)
			)
			(layer "F.Fab")
		)
		(fp_line
			(start -0.8636 -0.4572)
			(end 0.8636 -0.4572)
			(stroke
				(width 0.1)
				(type default)
			)
			(layer "F.Fab")
		)
		(fp_line
			(start -1.1938 0.4064)
			(end -1.1938 -0.4064)
			(stroke
				(width 0.1)
				(type default)
			)
			(layer "F.Fab")
		)
		(fp_line
			(start -1.1938 -0.4064)
			(end -0.8636 -0.4064)
			(stroke
				(width 0.1)
				(type default)
			)
			(layer "F.Fab")
		)
		(pad "1" smd rect
			(at -0.7366 0 90)
			(size 0.7112 0.8128)
			(layers "F.Cu" "F.Mask" "F.Paste")
			(net "PCEPLL3_VDDA18_PEX3_R")
		)
		(pad "2" smd rect
			(at 0.7366 0 90)
			(size 0.7112 0.8128)
			(layers "F.Cu" "F.Mask" "F.Paste")
			(net "GND")
		)
	)
	(footprint ""
		(layer "F.Cu")
		(at 215.551512 -231.416606 -90)
		(property "Reference" "R4555"
			(at 0 0 270)
			(layer "F.SilkS")
			(hide yes)
			(effects
				(font
					(size 1.27 1.27)
				)
			)
		)
		(property "Value" ""
			(at 0 0 270)
			(layer "F.Fab")
			(effects
				(font
					(size 1.27 1.27)
				)
			)
		)
		(duplicate_pad_numbers_are_jumpers no)
		(fp_line
			(start -0.7874 0.4064)
			(end -0.7874 -0.4064)
			(stroke
				(width 0.1524)
				(type default)
			)
			(layer "F.SilkS")
		)
		(fp_line
			(start 0.7874 0.4064)
			(end -0.7874 0.4064)
			(stroke
				(width 0.1524)
				(type default)
			)
			(layer "F.SilkS")
		)
		(fp_line
			(start -0.7874 -0.4064)
			(end 0.7874 -0.4064)
			(stroke
				(width 0.1524)
				(type default)
			)
			(layer "F.SilkS")
		)
		(fp_line
			(start 0.7874 -0.4064)
			(end 0.7874 0.4064)
			(stroke
				(width 0.1524)
				(type default)
			)
			(layer "F.SilkS")
		)
		(fp_line
			(start -0.67945 0.3048)
			(end -0.67945 -0.305054)
			(stroke
				(width 0.1)
				(type default)
			)
			(layer "F.Fab")
		)
		(fp_line
			(start -0.12065 0.3048)
			(end -0.67945 0.3048)
			(stroke
				(width 0.1)
				(type default)
			)
			(layer "F.Fab")
		)
		(fp_line
			(start 0.120396 0.3048)
			(end 0.120396 0.2794)
			(stroke
				(width 0.1)
				(type default)
			)
			(layer "F.Fab")
		)
		(fp_line
			(start 0.67945 0.3048)
			(end 0.120396 0.3048)
			(stroke
				(width 0.1)
				(type default)
			)
			(layer "F.Fab")
		)
		(fp_line
			(start -0.12065 0.2794)
			(end -0.12065 0.3048)
			(stroke
				(width 0.1)
				(type default)
			)
			(layer "F.Fab")
		)
		(fp_line
			(start 0.120396 0.2794)
			(end -0.12065 0.2794)
			(stroke
				(width 0.1)
				(type default)
			)
			(layer "F.Fab")
		)
		(fp_line
			(start -0.12065 -0.2794)
			(end 0.12065 -0.2794)
			(stroke
				(width 0.1)
				(type default)
			)
			(layer "F.Fab")
		)
		(fp_line
			(start 0.12065 -0.2794)
			(end 0.12065 -0.3048)
			(stroke
				(width 0.1)
				(type default)
			)
			(layer "F.Fab")
		)
		(fp_line
			(start 0.12065 -0.3048)
			(end 0.67945 -0.3048)
			(stroke
				(width 0.1)
				(type default)
			)
			(layer "F.Fab")
		)
		(fp_line
			(start 0.67945 -0.3048)
			(end 0.67945 0.3048)
			(stroke
				(width 0.1)
				(type default)
			)
			(layer "F.Fab")
		)
		(fp_line
			(start -0.67945 -0.305054)
			(end -0.12065 -0.305054)
			(stroke
				(width 0.1)
				(type default)
			)
			(layer "F.Fab")
		)
		(fp_line
			(start -0.12065 -0.305054)
			(end -0.12065 -0.2794)
			(stroke
				(width 0.1)
				(type default)
			)
			(layer "F.Fab")
		)
		(pad "1" smd circle
			(at -0.40005 0 270)
			(size 0 0)
			(layers "F.Cu" "F.Mask" "F.Paste")
			(net "GND")
		)
		(pad "2" smd circle
			(at 0.40005 0 270)
			(size 0 0)
			(layers "F.Cu" "F.Mask" "F.Paste")
			(net "BOARD_ID2")
		)
	)
	(footprint ""
		(layer "F.Cu")
		(at 272.798286 -252.356874 -90)
		(property "Reference" "R1357"
			(at 0 0 270)
			(layer "F.SilkS")
			(hide yes)
			(effects
				(font
					(size 1.27 1.27)
				)
			)
		)
		(property "Value" ""
			(at 0 0 270)
			(layer "F.Fab")
			(effects
				(font
					(size 1.27 1.27)
				)
			)
		)
		(duplicate_pad_numbers_are_jumpers no)
		(fp_line
			(start -0.7874 0.4064)
			(end -0.7874 -0.4064)
			(stroke
				(width 0.1524)
				(type default)
			)
			(layer "F.SilkS")
		)
		(fp_line
			(start 0.7874 0.4064)
			(end -0.7874 0.4064)
			(stroke
				(width 0.1524)
				(type default)
			)
			(layer "F.SilkS")
		)
		(fp_line
			(start -0.7874 -0.4064)
			(end 0.7874 -0.4064)
			(stroke
				(width 0.1524)
				(type default)
			)
			(layer "F.SilkS")
		)
		(fp_line
			(start 0.7874 -0.4064)
			(end 0.7874 0.4064)
			(stroke
				(width 0.1524)
				(type default)
			)
			(layer "F.SilkS")
		)
		(fp_line
			(start -0.67945 0.3048)
			(end -0.67945 -0.305054)
			(stroke
				(width 0.1)
				(type default)
			)
			(layer "F.Fab")
		)
		(fp_line
			(start -0.12065 0.3048)
			(end -0.67945 0.3048)
			(stroke
				(width 0.1)
				(type default)
			)
			(layer "F.Fab")
		)
		(fp_line
			(start 0.120396 0.3048)
			(end 0.120396 0.2794)
			(stroke
				(width 0.1)
				(type default)
			)
			(layer "F.Fab")
		)
		(fp_line
			(start 0.67945 0.3048)
			(end 0.120396 0.3048)
			(stroke
				(width 0.1)
				(type default)
			)
			(layer "F.Fab")
		)
		(fp_line
			(start -0.12065 0.2794)
			(end -0.12065 0.3048)
			(stroke
				(width 0.1)
				(type default)
			)
			(layer "F.Fab")
		)
		(fp_line
			(start 0.120396 0.2794)
			(end -0.12065 0.2794)
			(stroke
				(width 0.1)
				(type default)
			)
			(layer "F.Fab")
		)
		(fp_line
			(start -0.12065 -0.2794)
			(end 0.12065 -0.2794)
			(stroke
				(width 0.1)
				(type default)
			)
			(layer "F.Fab")
		)
		(fp_line
			(start 0.12065 -0.2794)
			(end 0.12065 -0.3048)
			(stroke
				(width 0.1)
				(type default)
			)
			(layer "F.Fab")
		)
		(fp_line
			(start 0.12065 -0.3048)
			(end 0.67945 -0.3048)
			(stroke
				(width 0.1)
				(type default)
			)
			(layer "F.Fab")
		)
		(fp_line
			(start 0.67945 -0.3048)
			(end 0.67945 0.3048)
			(stroke
				(width 0.1)
				(type default)
			)
			(layer "F.Fab")
		)
		(fp_line
			(start -0.67945 -0.305054)
			(end -0.12065 -0.305054)
			(stroke
				(width 0.1)
				(type default)
			)
			(layer "F.Fab")
		)
		(fp_line
			(start -0.12065 -0.305054)
			(end -0.12065 -0.2794)
			(stroke
				(width 0.1)
				(type default)
			)
			(layer "F.Fab")
		)
		(pad "1" smd circle
			(at -0.40005 0 270)
			(size 0 0)
			(layers "F.Cu" "F.Mask" "F.Paste")
			(net "GND")
		)
		(pad "2" smd circle
			(at 0.40005 0 270)
			(size 0 0)
			(layers "F.Cu" "F.Mask" "F.Paste")
			(net "PEX2_MODE_SEL1")
		)
	)
	(footprint ""
		(layer "F.Cu")
		(at 206.623158 -77.563472)
		(property "Reference" "R4309"
			(at 0 0 0)
			(layer "F.SilkS")
			(hide yes)
			(effects
				(font
					(size 1.27 1.27)
				)
			)
		)
		(property "Value" ""
			(at 0 0 0)
			(layer "F.Fab")
			(effects
				(font
					(size 1.27 1.27)
				)
			)
		)
		(duplicate_pad_numbers_are_jumpers no)
		(fp_line
			(start -0.7874 -0.4064)
			(end 0.7874 -0.4064)
			(stroke
				(width 0.1524)
				(type default)
			)
			(layer "F.SilkS")
		)
		(fp_line
			(start -0.7874 0.4064)
			(end -0.7874 -0.4064)
			(stroke
				(width 0.1524)
				(type default)
			)
			(layer "F.SilkS")
		)
		(fp_line
			(start 0.7874 -0.4064)
			(end 0.7874 0.4064)
			(stroke
				(width 0.1524)
				(type default)
			)
			(layer "F.SilkS")
		)
		(fp_line
			(start 0.7874 0.4064)
			(end -0.7874 0.4064)
			(stroke
				(width 0.1524)
				(type default)
			)
			(layer "F.SilkS")
		)
		(fp_line
			(start -0.67945 -0.305054)
			(end -0.12065 -0.305054)
			(stroke
				(width 0.1)
				(type default)
			)
			(layer "F.Fab")
		)
		(fp_line
			(start -0.67945 0.3048)
			(end -0.67945 -0.305054)
			(stroke
				(width 0.1)
				(type default)
			)
			(layer "F.Fab")
		)
		(fp_line
			(start -0.12065 -0.305054)
			(end -0.12065 -0.2794)
			(stroke
				(width 0.1)
				(type default)
			)
			(layer "F.Fab")
		)
		(fp_line
			(start -0.12065 -0.2794)
			(end 0.12065 -0.2794)
			(stroke
				(width 0.1)
				(type default)
			)
			(layer "F.Fab")
		)
		(fp_line
			(start -0.12065 0.2794)
			(end -0.12065 0.3048)
			(stroke
				(width 0.1)
				(type default)
			)
			(layer "F.Fab")
		)
		(fp_line
			(start -0.12065 0.3048)
			(end -0.67945 0.3048)
			(stroke
				(width 0.1)
				(type default)
			)
			(layer "F.Fab")
		)
		(fp_line
			(start 0.120396 0.2794)
			(end -0.12065 0.2794)
			(stroke
				(width 0.1)
				(type default)
			)
			(layer "F.Fab")
		)
		(fp_line
			(start 0.120396 0.3048)
			(end 0.120396 0.2794)
			(stroke
				(width 0.1)
				(type default)
			)
			(layer "F.Fab")
		)
		(fp_line
			(start 0.12065 -0.3048)
			(end 0.67945 -0.3048)
			(stroke
				(width 0.1)
				(type default)
			)
			(layer "F.Fab")
		)
		(fp_line
			(start 0.12065 -0.2794)
			(end 0.12065 -0.3048)
			(stroke
				(width 0.1)
				(type default)
			)
			(layer "F.Fab")
		)
		(fp_line
			(start 0.67945 -0.3048)
			(end 0.67945 0.3048)
			(stroke
				(width 0.1)
				(type default)
			)
			(layer "F.Fab")
		)
		(fp_line
			(start 0.67945 0.3048)
			(end 0.120396 0.3048)
			(stroke
				(width 0.1)
				(type default)
			)
			(layer "F.Fab")
		)
		(pad "1" smd circle
			(at -0.40005 0)
			(size 0 0)
			(layers "F.Cu" "F.Mask" "F.Paste")
			(net "SSD7_LED_R")
		)
		(pad "2" smd circle
			(at 0.40005 0)
			(size 0 0)
			(layers "F.Cu" "F.Mask" "F.Paste")
			(net "SSD7_LED")
		)
	)
)
